(kicad_pcb
	(version 20260206)
	(generator "pcbnew")
	(generator_version "10.0")
	(general
		(thickness 1.6)
		(legacy_teardrops no)
	)
	(paper "A4")
	(title_block
		(title "Bryce Canyon_IOM_IOC_16318-2_OCP.brd")
		(comment 1 "Bryce Canyon / footprints 651-658 of 1605")
	)
	(layers
		(0 "F.Cu" signal "TOP")
		(4 "In1.Cu" signal "L2GND")
		(6 "In2.Cu" signal "L3")
		(8 "In3.Cu" signal "L4VCC")
		(10 "In4.Cu" signal "L5VCC")
		(12 "In5.Cu" signal "L6")
		(14 "In6.Cu" signal "L7GND")
		(2 "B.Cu" signal "BOTTOM")
		(9 "F.Adhes" user "F.Adhesive")
		(11 "B.Adhes" user "B.Adhesive")
		(13 "F.Paste" user "Package Geometry/Pastemask Top")
		(15 "B.Paste" user "Package Geometry/Pastemask Bottom")
		(5 "F.SilkS" user "Ref Des/Silkscreen Top")
		(7 "B.SilkS" user "Ref Des/Silkscreen Bottom")
		(1 "F.Mask" user "Board Geometry/Soldermask Top")
		(3 "B.Mask" user "Board Geometry/Soldermask Bottom")
		(17 "Dwgs.User" user "User.Drawings")
		(19 "Cmts.User" user "User.Comments")
		(21 "Eco1.User" user "User.Eco1")
		(23 "Eco2.User" user "User.Eco2")
		(25 "Edge.Cuts" user "Board Geometry/Outline")
		(27 "Margin" user)
		(31 "F.CrtYd" user "Package Geometry/Place Bound Top")
		(29 "B.CrtYd" user "Package Geometry/Place Bound Bottom")
		(35 "F.Fab" user "Ref Des/Assembly Top")
		(33 "B.Fab" user "Ref Des/Assembly Bottom")
	)
	(footprint ""
		(layer "F.Cu")
		(at 88.773 -127.9144 -90)
		(property "Reference" "R715"
			(at 0 0 270)
			(layer "F.SilkS")
			(hide yes)
			(effects
				(font
					(size 1.27 1.27)
				)
			)
		)
		(property "Value" "0R2J-2-GP"
			(at 0.064008 -3.993896 270)
			(unlocked yes)
			(layer "F.Fab")
			(hide yes)
			(effects
				(font
					(size 1.016 1.016)
					(thickness 0.1524)
				)
			)
		)
		(property "Device Type" "R402H16"
			(at 0.064008 -5.517896 270)
			(unlocked yes)
			(layer "F.Fab")
			(hide yes)
			(effects
				(font
					(size 1.016 1.016)
					(thickness 0.1524)
				)
			)
		)
		(duplicate_pad_numbers_are_jumpers no)
		(fp_line
			(start -0.508 -0.9398)
			(end -0.508 0.9398)
			(stroke
				(width 0.1524)
				(type default)
			)
			(layer "F.SilkS")
		)
		(fp_line
			(start 0.508 -0.9398)
			(end -0.508 -0.9398)
			(stroke
				(width 0.1524)
				(type default)
			)
			(layer "F.SilkS")
		)
		(fp_rect
			(start -0.508 0.9398)
			(end 0.508 -0.9398)
			(stroke
				(width 0)
				(type default)
			)
			(fill no)
			(layer "F.CrtYd")
		)
		(fp_rect
			(start -0.508 0.9398)
			(end 0.508 -0.9398)
			(stroke
				(width 0)
				(type default)
			)
			(fill no)
			(layer "F.Fab")
		)
		(pad "1" smd custom
			(at 0 -0.4445 270)
			(size 0.1397 0.1397)
			(layers "F.Cu" "F.Mask" "F.Paste")
			(net "UART_SEL_MUX")
			(options
				(clearance outline)
				(anchor circle)
			)
			(primitives
				(gr_poly
					(pts
						(arc
							(start -0.1778 -0.2794)
							(mid -0.249642 -0.249642)
							(end -0.2794 -0.1778)
						)
						(arc
							(start -0.2794 0.1778)
							(mid -0.249642 0.249642)
							(end -0.1778 0.2794)
						)
						(arc
							(start 0.1778 0.2794)
							(mid 0.249642 0.249642)
							(end 0.2794 0.1778)
						)
						(arc
							(start 0.2794 -0.1778)
							(mid 0.249642 -0.249642)
							(end 0.1778 -0.2794)
						)
					)
					(width 0)
					(fill yes)
				)
			)
		)
		(pad "2" smd custom
			(at 0 0.4445 270)
			(size 0.1397 0.1397)
			(layers "F.Cu" "F.Mask" "F.Paste")
			(net "BMC_UART_SEL_OUT")
			(options
				(clearance outline)
				(anchor circle)
			)
			(primitives
				(gr_poly
					(pts
						(arc
							(start -0.1778 -0.2794)
							(mid -0.249642 -0.249642)
							(end -0.2794 -0.1778)
						)
						(arc
							(start -0.2794 0.1778)
							(mid -0.249642 0.249642)
							(end -0.1778 0.2794)
						)
						(arc
							(start 0.1778 0.2794)
							(mid 0.249642 0.249642)
							(end 0.2794 0.1778)
						)
						(arc
							(start 0.2794 -0.1778)
							(mid 0.249642 -0.249642)
							(end 0.1778 -0.2794)
						)
					)
					(width 0)
					(fill yes)
				)
			)
		)
	)
	(footprint ""
		(layer "F.Cu")
		(at 79.231744 -153.745184 180)
		(property "Reference" "R536"
			(at 0 0 180)
			(layer "F.SilkS")
			(hide yes)
			(effects
				(font
					(size 1.27 1.27)
				)
			)
		)
		(property "Value" "0R5J-5-GP"
			(at 0 -8.9535 180)
			(unlocked yes)
			(layer "F.Fab")
			(hide yes)
			(effects
				(font
					(size 1.27 1.016)
					(thickness 0.1524)
				)
			)
		)
		(property "Device Type" "R805H24"
			(at 0 -10.6299 180)
			(unlocked yes)
			(layer "F.Fab")
			(hide yes)
			(effects
				(font
					(size 1.27 1.016)
					(thickness 0.1524)
				)
			)
		)
		(duplicate_pad_numbers_are_jumpers no)
		(fp_line
			(start 0.889 1.7018)
			(end 0.889 -0.508)
			(stroke
				(width 0.1524)
				(type default)
			)
			(layer "F.SilkS")
		)
		(fp_line
			(start 0.889 -1.7018)
			(end 0.889 -0.381)
			(stroke
				(width 0.1524)
				(type default)
			)
			(layer "F.SilkS")
		)
		(fp_line
			(start 0.889 -1.7018)
			(end -0.889 -1.7018)
			(stroke
				(width 0.1524)
				(type default)
			)
			(layer "F.SilkS")
		)
		(fp_line
			(start -0.889 1.7018)
			(end 0.889 1.7018)
			(stroke
				(width 0.1524)
				(type default)
			)
			(layer "F.SilkS")
		)
		(fp_line
			(start -0.889 0.0762)
			(end -0.889 1.7018)
			(stroke
				(width 0.1524)
				(type default)
			)
			(layer "F.SilkS")
		)
		(fp_line
			(start -0.889 -1.7018)
			(end -0.889 0.2794)
			(stroke
				(width 0.1524)
				(type default)
			)
			(layer "F.SilkS")
		)
		(fp_poly
			(pts
				(xy 0.9652 -1.778) (xy 0.9652 1.778) (xy -0.9652 1.778) (xy -0.9652 -1.778)
			)
			(stroke
				(width 0)
				(type default)
			)
			(fill no)
			(layer "F.CrtYd")
		)
		(fp_rect
			(start -0.9652 1.778)
			(end 0.9652 -1.778)
			(stroke
				(width 0)
				(type default)
			)
			(fill no)
			(layer "F.Fab")
		)
		(pad "1" smd rect
			(at 0 -0.9652 180)
			(size 1.397 1.143)
			(layers "F.Cu" "F.Mask" "F.Paste")
			(net "P1V15_STBY")
		)
		(pad "2" smd rect
			(at 0 0.9652 180)
			(size 1.397 1.143)
			(layers "F.Cu" "F.Mask" "F.Paste")
			(net "TPS74801_P1V15_STBY_OUT")
		)
	)
	(footprint ""
		(layer "F.Cu")
		(at 63.459868 -180.08854)
		(property "Reference" "R356"
			(at 0 0 0)
			(layer "F.SilkS")
			(hide yes)
			(effects
				(font
					(size 1.27 1.27)
				)
			)
		)
		(property "Value" "0R2J-2-GP"
			(at 0.064008 -3.993896 0)
			(unlocked yes)
			(layer "F.Fab")
			(hide yes)
			(effects
				(font
					(size 1.016 1.016)
					(thickness 0.1524)
				)
			)
		)
		(property "Device Type" "R402H16"
			(at 0.064008 -5.517896 0)
			(unlocked yes)
			(layer "F.Fab")
			(hide yes)
			(effects
				(font
					(size 1.016 1.016)
					(thickness 0.1524)
				)
			)
		)
		(duplicate_pad_numbers_are_jumpers no)
		(fp_line
			(start -0.508 -0.9398)
			(end -0.508 0.9398)
			(stroke
				(width 0.1524)
				(type default)
			)
			(layer "F.SilkS")
		)
		(fp_line
			(start 0.508 -0.9398)
			(end -0.508 -0.9398)
			(stroke
				(width 0.1524)
				(type default)
			)
			(layer "F.SilkS")
		)
		(fp_rect
			(start -0.508 0.9398)
			(end 0.508 -0.9398)
			(stroke
				(width 0)
				(type default)
			)
			(fill no)
			(layer "F.CrtYd")
		)
		(fp_rect
			(start -0.508 0.9398)
			(end 0.508 -0.9398)
			(stroke
				(width 0)
				(type default)
			)
			(fill no)
			(layer "F.Fab")
		)
		(pad "1" smd custom
			(at 0 -0.4445)
			(size 0.1397 0.1397)
			(layers "F.Cu" "F.Mask" "F.Paste")
			(net "IOM_STBY_PGOOD")
			(options
				(clearance outline)
				(anchor circle)
			)
			(primitives
				(gr_poly
					(pts
						(arc
							(start -0.1778 -0.2794)
							(mid -0.249642 -0.249642)
							(end -0.2794 -0.1778)
						)
						(arc
							(start -0.2794 0.1778)
							(mid -0.249642 0.249642)
							(end -0.1778 0.2794)
						)
						(arc
							(start 0.1778 0.2794)
							(mid 0.249642 0.249642)
							(end 0.2794 0.1778)
						)
						(arc
							(start 0.2794 -0.1778)
							(mid 0.249642 -0.249642)
							(end 0.1778 -0.2794)
						)
					)
					(width 0)
					(fill yes)
				)
			)
		)
		(pad "2" smd custom
			(at 0 0.4445)
			(size 0.1397 0.1397)
			(layers "F.Cu" "F.Mask" "F.Paste")
			(net "FM_BMC_RESET_N")
			(options
				(clearance outline)
				(anchor circle)
			)
			(primitives
				(gr_poly
					(pts
						(arc
							(start -0.1778 -0.2794)
							(mid -0.249642 -0.249642)
							(end -0.2794 -0.1778)
						)
						(arc
							(start -0.2794 0.1778)
							(mid -0.249642 0.249642)
							(end -0.1778 0.2794)
						)
						(arc
							(start 0.1778 0.2794)
							(mid 0.249642 0.249642)
							(end 0.2794 0.1778)
						)
						(arc
							(start 0.2794 -0.1778)
							(mid 0.249642 -0.249642)
							(end 0.1778 -0.2794)
						)
					)
					(width 0)
					(fill yes)
				)
			)
		)
	)
	(footprint ""
		(layer "F.Cu")
		(at 82.441796 -175.58258 90)
		(property "Reference" "C191"
			(at 0 0 90)
			(layer "F.SilkS")
			(hide yes)
			(effects
				(font
					(size 1.27 1.27)
				)
			)
		)
		(property "Value" "SC10U6D3V5KX-4GP"
			(at -0.0762 -6.1214 90)
			(unlocked yes)
			(layer "F.Fab")
			(hide yes)
			(effects
				(font
					(size 1.016 1.016)
					(thickness 0.1524)
				)
			)
		)
		(property "Device Type" "C805H58"
			(at -0.0762 -8.1534 90)
			(unlocked yes)
			(layer "F.Fab")
			(hide yes)
			(effects
				(font
					(size 1.016 1.016)
					(thickness 0.1524)
				)
			)
		)
		(duplicate_pad_numbers_are_jumpers no)
		(fp_line
			(start 0.635 0)
			(end -0.635 0)
			(stroke
				(width 0.508)
				(type default)
			)
			(layer "F.SilkS")
		)
		(fp_rect
			(start -0.9652 1.778)
			(end 0.9652 -1.778)
			(stroke
				(width 0)
				(type default)
			)
			(fill no)
			(layer "F.CrtYd")
		)
		(fp_poly
			(pts
				(xy -0.9652 -1.778) (xy 0.9652 -1.778) (xy 0.9652 1.778) (xy -0.9652 1.778)
			)
			(stroke
				(width 0)
				(type default)
			)
			(fill no)
			(layer "F.Fab")
		)
		(pad "1" smd rect
			(at 0 -0.9652 90)
			(size 1.397 1.143)
			(layers "F.Cu" "F.Mask" "F.Paste")
			(net "TPS74801_P2V5_STBY_OUT")
		)
		(pad "2" smd rect
			(at 0 0.9652 90)
			(size 1.397 1.143)
			(layers "F.Cu" "F.Mask" "F.Paste")
			(net "GND")
		)
	)
	(footprint ""
		(layer "F.Cu")
		(at 93.124528 -49.429416 180)
		(property "Reference" "C507"
			(at 0 0 180)
			(layer "F.SilkS")
			(hide yes)
			(effects
				(font
					(size 1.27 1.27)
				)
			)
		)
		(property "Value" "SCD1U16V2KX-3GP"
			(at 1.1811 -2.7051 180)
			(unlocked yes)
			(layer "F.Fab")
			(hide yes)
			(effects
				(font
					(size 1.016 1.016)
					(thickness 0.1524)
				)
			)
		)
		(property "Device Type" "C402H22"
			(at 1.1811 -4.2291 180)
			(unlocked yes)
			(layer "F.Fab")
			(hide yes)
			(effects
				(font
					(size 1.016 1.016)
					(thickness 0.1524)
				)
			)
		)
		(duplicate_pad_numbers_are_jumpers no)
		(fp_rect
			(start -0.4318 0.9525)
			(end 0.4318 -0.9525)
			(stroke
				(width 0)
				(type default)
			)
			(fill no)
			(layer "F.CrtYd")
		)
		(fp_rect
			(start -0.4318 0.9525)
			(end 0.4318 -0.9525)
			(stroke
				(width 0)
				(type default)
			)
			(fill no)
			(layer "F.Fab")
		)
		(pad "1" smd custom
			(at 0 -0.4445 180)
			(size 0.1524 0.1524)
			(layers "F.Cu" "F.Mask" "F.Paste")
			(net "P3V3_EN_R")
			(options
				(clearance outline)
				(anchor circle)
			)
			(primitives
				(gr_poly
					(pts
						(arc
							(start 0.3048 -0.2032)
							(mid 0.275042 -0.275042)
							(end 0.2032 -0.3048)
						)
						(arc
							(start -0.2032 -0.3048)
							(mid -0.275042 -0.275042)
							(end -0.3048 -0.2032)
						)
						(arc
							(start -0.3048 0.2032)
							(mid -0.275042 0.275042)
							(end -0.2032 0.3048)
						)
						(arc
							(start 0.2032 0.3048)
							(mid 0.275042 0.275042)
							(end 0.3048 0.2032)
						)
					)
					(width 0)
					(fill yes)
				)
			)
		)
		(pad "2" smd custom
			(at 0 0.4445 180)
			(size 0.1524 0.1524)
			(layers "F.Cu" "F.Mask" "F.Paste")
			(net "GND")
			(options
				(clearance outline)
				(anchor circle)
			)
			(primitives
				(gr_poly
					(pts
						(arc
							(start 0.3048 -0.2032)
							(mid 0.275042 -0.275042)
							(end 0.2032 -0.3048)
						)
						(arc
							(start -0.2032 -0.3048)
							(mid -0.275042 -0.275042)
							(end -0.3048 -0.2032)
						)
						(arc
							(start -0.3048 0.2032)
							(mid -0.275042 0.275042)
							(end -0.2032 0.3048)
						)
						(arc
							(start 0.2032 0.3048)
							(mid 0.275042 0.275042)
							(end 0.3048 0.2032)
						)
					)
					(width 0)
					(fill yes)
				)
			)
		)
	)
	(footprint ""
		(layer "F.Cu")
		(at 133.9088 -12.5476 -90)
		(property "Reference" "R443"
			(at 0 0 270)
			(layer "F.SilkS")
			(hide yes)
			(effects
				(font
					(size 1.27 1.27)
				)
			)
		)
		(property "Value" "10R2F-L-GP"
			(at 0.064008 -3.993896 270)
			(unlocked yes)
			(layer "F.Fab")
			(hide yes)
			(effects
				(font
					(size 1.016 1.016)
					(thickness 0.1524)
				)
			)
		)
		(property "Device Type" "R402H14"
			(at 0.064008 -5.517896 270)
			(unlocked yes)
			(layer "F.Fab")
			(hide yes)
			(effects
				(font
					(size 1.016 1.016)
					(thickness 0.1524)
				)
			)
		)
		(duplicate_pad_numbers_are_jumpers no)
		(fp_line
			(start -0.508 -0.9398)
			(end -0.508 0.9398)
			(stroke
				(width 0.1524)
				(type default)
			)
			(layer "F.SilkS")
		)
		(fp_line
			(start 0.508 -0.9398)
			(end -0.508 -0.9398)
			(stroke
				(width 0.1524)
				(type default)
			)
			(layer "F.SilkS")
		)
		(fp_rect
			(start -0.508 0.9398)
			(end 0.508 -0.9398)
			(stroke
				(width 0)
				(type default)
			)
			(fill no)
			(layer "F.CrtYd")
		)
		(fp_rect
			(start -0.508 0.9398)
			(end 0.508 -0.9398)
			(stroke
				(width 0)
				(type default)
			)
			(fill no)
			(layer "F.Fab")
		)
		(pad "1" smd custom
			(at 0 -0.4445 270)
			(size 0.1397 0.1397)
			(layers "F.Cu" "F.Mask" "F.Paste")
			(net "MB0_CM_SENSE_R1_N")
			(options
				(clearance outline)
				(anchor circle)
			)
			(primitives
				(gr_poly
					(pts
						(arc
							(start -0.1778 -0.2794)
							(mid -0.249642 -0.249642)
							(end -0.2794 -0.1778)
						)
						(arc
							(start -0.2794 0.1778)
							(mid -0.249642 0.249642)
							(end -0.1778 0.2794)
						)
						(arc
							(start 0.1778 0.2794)
							(mid 0.249642 0.249642)
							(end 0.2794 0.1778)
						)
						(arc
							(start 0.2794 -0.1778)
							(mid 0.249642 -0.249642)
							(end 0.1778 -0.2794)
						)
					)
					(width 0)
					(fill yes)
				)
			)
		)
		(pad "2" smd custom
			(at 0 0.4445 270)
			(size 0.1397 0.1397)
			(layers "F.Cu" "F.Mask" "F.Paste")
			(net "ADM1278_HS_N")
			(options
				(clearance outline)
				(anchor circle)
			)
			(primitives
				(gr_poly
					(pts
						(arc
							(start -0.1778 -0.2794)
							(mid -0.249642 -0.249642)
							(end -0.2794 -0.1778)
						)
						(arc
							(start -0.2794 0.1778)
							(mid -0.249642 0.249642)
							(end -0.1778 0.2794)
						)
						(arc
							(start 0.1778 0.2794)
							(mid 0.249642 0.249642)
							(end 0.2794 0.1778)
						)
						(arc
							(start 0.2794 -0.1778)
							(mid 0.249642 -0.249642)
							(end 0.1778 -0.2794)
						)
					)
					(width 0)
					(fill yes)
				)
			)
		)
	)
	(footprint ""
		(layer "F.Cu")
		(at 44.958 -157.9118)
		(property "Reference" "R173"
			(at 0 0 0)
			(layer "F.SilkS")
			(hide yes)
			(effects
				(font
					(size 1.27 1.27)
				)
			)
		)
		(property "Value" "0R2J-2-GP"
			(at 0.064008 -3.993896 0)
			(unlocked yes)
			(layer "F.Fab")
			(hide yes)
			(effects
				(font
					(size 1.016 1.016)
					(thickness 0.1524)
				)
			)
		)
		(property "Device Type" "R402H16"
			(at 0.064008 -5.517896 0)
			(unlocked yes)
			(layer "F.Fab")
			(hide yes)
			(effects
				(font
					(size 1.016 1.016)
					(thickness 0.1524)
				)
			)
		)
		(duplicate_pad_numbers_are_jumpers no)
		(fp_line
			(start -0.508 -0.9398)
			(end -0.508 0.9398)
			(stroke
				(width 0.1524)
				(type default)
			)
			(layer "F.SilkS")
		)
		(fp_line
			(start 0.508 -0.9398)
			(end -0.508 -0.9398)
			(stroke
				(width 0.1524)
				(type default)
			)
			(layer "F.SilkS")
		)
		(fp_rect
			(start -0.508 0.9398)
			(end 0.508 -0.9398)
			(stroke
				(width 0)
				(type default)
			)
			(fill no)
			(layer "F.CrtYd")
		)
		(fp_rect
			(start -0.508 0.9398)
			(end 0.508 -0.9398)
			(stroke
				(width 0)
				(type default)
			)
			(fill no)
			(layer "F.Fab")
		)
		(pad "1" smd custom
			(at 0 -0.4445)
			(size 0.1397 0.1397)
			(layers "F.Cu" "F.Mask" "F.Paste")
			(net "I2C_M2_1_SCL")
			(options
				(clearance outline)
				(anchor circle)
			)
			(primitives
				(gr_poly
					(pts
						(arc
							(start -0.1778 -0.2794)
							(mid -0.249642 -0.249642)
							(end -0.2794 -0.1778)
						)
						(arc
							(start -0.2794 0.1778)
							(mid -0.249642 0.249642)
							(end -0.1778 0.2794)
						)
						(arc
							(start 0.1778 0.2794)
							(mid 0.249642 0.249642)
							(end 0.2794 0.1778)
						)
						(arc
							(start 0.2794 -0.1778)
							(mid 0.249642 -0.249642)
							(end 0.1778 -0.2794)
						)
					)
					(width 0)
					(fill yes)
				)
			)
		)
		(pad "2" smd custom
			(at 0 0.4445)
			(size 0.1397 0.1397)
			(layers "F.Cu" "F.Mask" "F.Paste")
			(net "BMC_SMB8_CLK")
			(options
				(clearance outline)
				(anchor circle)
			)
			(primitives
				(gr_poly
					(pts
						(arc
							(start -0.1778 -0.2794)
							(mid -0.249642 -0.249642)
							(end -0.2794 -0.1778)
						)
						(arc
							(start -0.2794 0.1778)
							(mid -0.249642 0.249642)
							(end -0.1778 0.2794)
						)
						(arc
							(start 0.1778 0.2794)
							(mid 0.249642 0.249642)
							(end 0.2794 0.1778)
						)
						(arc
							(start 0.2794 -0.1778)
							(mid 0.249642 -0.249642)
							(end 0.1778 -0.2794)
						)
					)
					(width 0)
					(fill yes)
				)
			)
		)
	)
	(footprint ""
		(layer "F.Cu")
		(at 54.0004 -131.7498)
		(property "Reference" "R147"
			(at 0 0 0)
			(layer "F.SilkS")
			(hide yes)
			(effects
				(font
					(size 1.27 1.27)
				)
			)
		)
		(property "Value" "100KR2F-L1-GP"
			(at 0.064008 -3.993896 0)
			(unlocked yes)
			(layer "F.Fab")
			(hide yes)
			(effects
				(font
					(size 1.016 1.016)
					(thickness 0.1524)
				)
			)
		)
		(property "Device Type" "R402H16"
			(at 0.064008 -5.517896 0)
			(unlocked yes)
			(layer "F.Fab")
			(hide yes)
			(effects
				(font
					(size 1.016 1.016)
					(thickness 0.1524)
				)
			)
		)
		(duplicate_pad_numbers_are_jumpers no)
		(fp_line
			(start -0.508 -0.9398)
			(end -0.508 0.9398)
			(stroke
				(width 0.1524)
				(type default)
			)
			(layer "F.SilkS")
		)
		(fp_line
			(start 0.508 -0.9398)
			(end -0.508 -0.9398)
			(stroke
				(width 0.1524)
				(type default)
			)
			(layer "F.SilkS")
		)
		(fp_rect
			(start -0.508 0.9398)
			(end 0.508 -0.9398)
			(stroke
				(width 0)
				(type default)
			)
			(fill no)
			(layer "F.CrtYd")
		)
		(fp_rect
			(start -0.508 0.9398)
			(end 0.508 -0.9398)
			(stroke
				(width 0)
				(type default)
			)
			(fill no)
			(layer "F.Fab")
		)
		(pad "1" smd custom
			(at 0 -0.4445)
			(size 0.1397 0.1397)
			(layers "F.Cu" "F.Mask" "F.Paste")
			(net "LPC_CPU_FRAME_N")
			(options
				(clearance outline)
				(anchor circle)
			)
			(primitives
				(gr_poly
					(pts
						(arc
							(start -0.1778 -0.2794)
							(mid -0.249642 -0.249642)
							(end -0.2794 -0.1778)
						)
						(arc
							(start -0.2794 0.1778)
							(mid -0.249642 0.249642)
							(end -0.1778 0.2794)
						)
						(arc
							(start 0.1778 0.2794)
							(mid 0.249642 0.249642)
							(end 0.2794 0.1778)
						)
						(arc
							(start 0.2794 -0.1778)
							(mid 0.249642 -0.249642)
							(end 0.1778 -0.2794)
						)
					)
					(width 0)
					(fill yes)
				)
			)
		)
		(pad "2" smd custom
			(at 0 0.4445)
			(size 0.1397 0.1397)
			(layers "F.Cu" "F.Mask" "F.Paste")
			(net "GND")
			(options
				(clearance outline)
				(anchor circle)
			)
			(primitives
				(gr_poly
					(pts
						(arc
							(start -0.1778 -0.2794)
							(mid -0.249642 -0.249642)
							(end -0.2794 -0.1778)
						)
						(arc
							(start -0.2794 0.1778)
							(mid -0.249642 0.249642)
							(end -0.1778 0.2794)
						)
						(arc
							(start 0.1778 0.2794)
							(mid 0.249642 0.249642)
							(end 0.2794 0.1778)
						)
						(arc
							(start 0.2794 -0.1778)
							(mid 0.249642 -0.249642)
							(end 0.1778 -0.2794)
						)
					)
					(width 0)
					(fill yes)
				)
			)
		)
	)
)
